# S9S_MB_2U (Grand Teton) — schematic netlist excerpt (pin names and nets, part order shuffled) for the footprints in the layout excerpt that follows; sources: Cadence DE-HDL packaged netlist, KiCad conversion of 03242023_DA0F0TMBIJ0_F0T_Motherboard_J_brd_V01_OCP.brd

R160  Q_RES  0 5% CHIP  pkg 0402LF  page 124 : A = PWRGD_DRAMPWRGD_CPU0_AB_R_LVC1 ; B = PWRGD_DRAMPWRGD_CPU0_AB_LVC1_R2
C463  Q_CAP  47UF 4V 20% X6S  pkg C0805  page 79 : A = PVCCD_HV_CPU1 ; B = GND
R968  Q_RES  1K 1% CHIP  pkg 0402LF  page 235 : A = P3V3_AUX ; B = SMB_PEHPCPU1_LVC3_SDA

(kicad_pcb
	(version 20260206)
	(generator "pcbnew")
	(generator_version "10.0")
	(general
		(thickness 1.6)
		(legacy_teardrops no)
	)
	(paper "A4")
	(title_block
		(title "03242023_DA0F0TMBIJ0_F0T_Motherboard_J_brd_V01_OCP.brd")
		(comment 1 "Grand Teton / footprints 6057-6059 of 6105")
	)
	(layers
		(0 "F.Cu" signal "TOP")
		(4 "In1.Cu" signal "GND")
		(6 "In2.Cu" signal "IN1")
		(8 "In3.Cu" signal "GND1")
		(10 "In4.Cu" signal "IN2")
		(12 "In5.Cu" signal "GND2")
		(14 "In6.Cu" signal "IN3")
		(16 "In7.Cu" signal "GND3")
		(18 "In8.Cu" signal "VCC")
		(20 "In9.Cu" signal "VCC1")
		(22 "In10.Cu" signal "GND4")
		(24 "In11.Cu" signal "IN4")
		(26 "In12.Cu" signal "GND5")
		(28 "In13.Cu" signal "IN5")
		(30 "In14.Cu" signal "GND6")
		(32 "In15.Cu" signal "IN6")
		(34 "In16.Cu" signal "GND7")
		(2 "B.Cu" signal "BOTTOM")
		(9 "F.Adhes" user "F.Adhesive")
		(11 "B.Adhes" user "B.Adhesive")
		(13 "F.Paste" user "Package Geometry/Pastemask Top")
		(15 "B.Paste" user "Package Geometry/Pastemask Bottom")
		(5 "F.SilkS" user "Ref Des/Silkscreen Top")
		(7 "B.SilkS" user "Ref Des/Silkscreen Bottom")
		(1 "F.Mask" user "Board Geometry/Soldermask Top")
		(3 "B.Mask" user "Board Geometry/Soldermask Bottom")
		(17 "Dwgs.User" user "User.Drawings")
		(19 "Cmts.User" user "User.Comments")
		(21 "Eco1.User" user "User.Eco1")
		(23 "Eco2.User" user "User.Eco2")
		(25 "Edge.Cuts" user "Board Geometry/Outline")
		(27 "Margin" user)
		(31 "F.CrtYd" user "Package Geometry/Place Bound Top")
		(29 "B.CrtYd" user "Package Geometry/Place Bound Bottom")
		(35 "F.Fab" user "Ref Des/Assembly Top")
		(33 "B.Fab" user "Ref Des/Assembly Bottom")
	)
	(footprint ""
		(layer "B.Cu")
		(at 175.174402 -103.098346 90)
		(property "Reference" "R160"
			(at 0 0 90)
			(layer "B.SilkS")
			(hide yes)
			(effects
				(font
					(size 1.27 1.27)
				)
				(justify mirror)
			)
		)
		(property "Value" ""
			(at 0 0 90)
			(layer "B.Fab")
			(effects
				(font
					(size 1.27 1.27)
				)
				(justify mirror)
			)
		)
		(duplicate_pad_numbers_are_jumpers no)
		(fp_line
			(start 0.7874 -0.4064)
			(end -0.7874 -0.4064)
			(stroke
				(width 0.1524)
				(type default)
			)
			(layer "B.SilkS")
		)
		(fp_line
			(start -0.7874 -0.4064)
			(end -0.7874 0.4064)
			(stroke
				(width 0.1524)
				(type default)
			)
			(layer "B.SilkS")
		)
		(fp_line
			(start 0.7874 0.4064)
			(end 0.7874 -0.4064)
			(stroke
				(width 0.1524)
				(type default)
			)
			(layer "B.SilkS")
		)
		(fp_line
			(start -0.7874 0.4064)
			(end 0.7874 0.4064)
			(stroke
				(width 0.1524)
				(type default)
			)
			(layer "B.SilkS")
		)
		(fp_line
			(start 0.67945 -0.305054)
			(end 0.12065 -0.305054)
			(stroke
				(width 0.1)
				(type default)
			)
			(layer "B.Fab")
		)
		(fp_line
			(start 0.12065 -0.305054)
			(end 0.12065 -0.2794)
			(stroke
				(width 0.1)
				(type default)
			)
			(layer "B.Fab")
		)
		(fp_line
			(start -0.12065 -0.3048)
			(end -0.67945 -0.3048)
			(stroke
				(width 0.1)
				(type default)
			)
			(layer "B.Fab")
		)
		(fp_line
			(start -0.67945 -0.3048)
			(end -0.67945 0.3048)
			(stroke
				(width 0.1)
				(type default)
			)
			(layer "B.Fab")
		)
		(fp_line
			(start 0.12065 -0.2794)
			(end -0.12065 -0.2794)
			(stroke
				(width 0.1)
				(type default)
			)
			(layer "B.Fab")
		)
		(fp_line
			(start -0.12065 -0.2794)
			(end -0.12065 -0.3048)
			(stroke
				(width 0.1)
				(type default)
			)
			(layer "B.Fab")
		)
		(fp_line
			(start 0.12065 0.2794)
			(end 0.12065 0.3048)
			(stroke
				(width 0.1)
				(type default)
			)
			(layer "B.Fab")
		)
		(fp_line
			(start -0.120396 0.2794)
			(end 0.12065 0.2794)
			(stroke
				(width 0.1)
				(type default)
			)
			(layer "B.Fab")
		)
		(fp_line
			(start 0.67945 0.3048)
			(end 0.67945 -0.305054)
			(stroke
				(width 0.1)
				(type default)
			)
			(layer "B.Fab")
		)
		(fp_line
			(start 0.12065 0.3048)
			(end 0.67945 0.3048)
			(stroke
				(width 0.1)
				(type default)
			)
			(layer "B.Fab")
		)
		(fp_line
			(start -0.120396 0.3048)
			(end -0.120396 0.2794)
			(stroke
				(width 0.1)
				(type default)
			)
			(layer "B.Fab")
		)
		(fp_line
			(start -0.67945 0.3048)
			(end -0.120396 0.3048)
			(stroke
				(width 0.1)
				(type default)
			)
			(layer "B.Fab")
		)
		(pad "1" smd circle
			(at 0.40005 0 270)
			(size 0 0)
			(layers "B.Cu" "B.Mask" "B.Paste")
			(net "PWRGD_DRAMPWRGD_CPU0_AB_R_LVC1")
		)
		(pad "2" smd circle
			(at -0.40005 0 270)
			(size 0 0)
			(layers "B.Cu" "B.Mask" "B.Paste")
			(net "PWRGD_DRAMPWRGD_CPU0_AB_LVC1_R2")
		)
	)
	(footprint ""
		(layer "B.Cu")
		(at 111.310166 -212.049868)
		(property "Reference" "C463"
			(at 0 0 0)
			(layer "B.SilkS")
			(hide yes)
			(effects
				(font
					(size 1.27 1.27)
				)
				(justify mirror)
			)
		)
		(property "Value" ""
			(at 0 0 0)
			(layer "B.Fab")
			(effects
				(font
					(size 1.27 1.27)
				)
				(justify mirror)
			)
		)
		(duplicate_pad_numbers_are_jumpers no)
		(fp_line
			(start -1.524 -0.762)
			(end -1.524 0.762)
			(stroke
				(width 0.1524)
				(type default)
			)
			(layer "B.SilkS")
		)
		(fp_line
			(start -1.524 0.762)
			(end 1.524 0.762)
			(stroke
				(width 0.1524)
				(type default)
			)
			(layer "B.SilkS")
		)
		(fp_line
			(start 1.524 -0.762)
			(end -1.524 -0.762)
			(stroke
				(width 0.1524)
				(type default)
			)
			(layer "B.SilkS")
		)
		(fp_line
			(start 1.524 0.762)
			(end 1.524 -0.762)
			(stroke
				(width 0.1524)
				(type default)
			)
			(layer "B.SilkS")
		)
		(fp_line
			(start -1.1049 -0.724916)
			(end 1.1049 -0.724916)
			(stroke
				(width 0.1)
				(type default)
			)
			(layer "B.Fab")
		)
		(fp_line
			(start -1.1049 0.724916)
			(end -1.1049 -0.724916)
			(stroke
				(width 0.1)
				(type default)
			)
			(layer "B.Fab")
		)
		(fp_line
			(start 1.1049 -0.724916)
			(end 1.1049 0.724916)
			(stroke
				(width 0.1)
				(type default)
			)
			(layer "B.Fab")
		)
		(fp_line
			(start 1.1049 0.724916)
			(end -1.1049 0.724916)
			(stroke
				(width 0.1)
				(type default)
			)
			(layer "B.Fab")
		)
		(pad "1" smd rect
			(at 0.889 0)
			(size 1.016 1.27)
			(layers "B.Cu" "B.Mask" "B.Paste")
			(net "PVCCD_HV_CPU1")
		)
		(pad "2" smd rect
			(at -0.889 0)
			(size 1.016 1.27)
			(layers "B.Cu" "B.Mask" "B.Paste")
			(net "GND")
		)
	)
	(footprint ""
		(layer "B.Cu")
		(at 10.558272 -183.482996)
		(property "Reference" "R968"
			(at 0 0 0)
			(layer "B.SilkS")
			(hide yes)
			(effects
				(font
					(size 1.27 1.27)
				)
				(justify mirror)
			)
		)
		(property "Value" ""
			(at 0 0 0)
			(layer "B.Fab")
			(effects
				(font
					(size 1.27 1.27)
				)
				(justify mirror)
			)
		)
		(duplicate_pad_numbers_are_jumpers no)
		(fp_line
			(start -0.7874 -0.4064)
			(end -0.7874 0.4064)
			(stroke
				(width 0.1524)
				(type default)
			)
			(layer "B.SilkS")
		)
		(fp_line
			(start -0.7874 0.4064)
			(end 0.7874 0.4064)
			(stroke
				(width 0.1524)
				(type default)
			)
			(layer "B.SilkS")
		)
		(fp_line
			(start 0.7874 -0.4064)
			(end -0.7874 -0.4064)
			(stroke
				(width 0.1524)
				(type default)
			)
			(layer "B.SilkS")
		)
		(fp_line
			(start 0.7874 0.4064)
			(end 0.7874 -0.4064)
			(stroke
				(width 0.1524)
				(type default)
			)
			(layer "B.SilkS")
		)
		(fp_line
			(start -0.67945 -0.3048)
			(end -0.67945 0.3048)
			(stroke
				(width 0.1)
				(type default)
			)
			(layer "B.Fab")
		)
		(fp_line
			(start -0.67945 0.3048)
			(end -0.120396 0.3048)
			(stroke
				(width 0.1)
				(type default)
			)
			(layer "B.Fab")
		)
		(fp_line
			(start -0.12065 -0.3048)
			(end -0.67945 -0.3048)
			(stroke
				(width 0.1)
				(type default)
			)
			(layer "B.Fab")
		)
		(fp_line
			(start -0.12065 -0.2794)
			(end -0.12065 -0.3048)
			(stroke
				(width 0.1)
				(type default)
			)
			(layer "B.Fab")
		)
		(fp_line
			(start -0.120396 0.2794)
			(end 0.12065 0.2794)
			(stroke
				(width 0.1)
				(type default)
			)
			(layer "B.Fab")
		)
		(fp_line
			(start -0.120396 0.3048)
			(end -0.120396 0.2794)
			(stroke
				(width 0.1)
				(type default)
			)
			(layer "B.Fab")
		)
		(fp_line
			(start 0.12065 -0.305054)
			(end 0.12065 -0.2794)
			(stroke
				(width 0.1)
				(type default)
			)
			(layer "B.Fab")
		)
		(fp_line
			(start 0.12065 -0.2794)
			(end -0.12065 -0.2794)
			(stroke
				(width 0.1)
				(type default)
			)
			(layer "B.Fab")
		)
		(fp_line
			(start 0.12065 0.2794)
			(end 0.12065 0.3048)
			(stroke
				(width 0.1)
				(type default)
			)
			(layer "B.Fab")
		)
		(fp_line
			(start 0.12065 0.3048)
			(end 0.67945 0.3048)
			(stroke
				(width 0.1)
				(type default)
			)
			(layer "B.Fab")
		)
		(fp_line
			(start 0.67945 -0.305054)
			(end 0.12065 -0.305054)
			(stroke
				(width 0.1)
				(type default)
			)
			(layer "B.Fab")
		)
		(fp_line
			(start 0.67945 0.3048)
			(end 0.67945 -0.305054)
			(stroke
				(width 0.1)
				(type default)
			)
			(layer "B.Fab")
		)
		(pad "1" smd circle
			(at 0.40005 0 180)
			(size 0 0)
			(layers "B.Cu" "B.Mask" "B.Paste")
			(net "P3V3_AUX")
		)
		(pad "2" smd circle
			(at -0.40005 0 180)
			(size 0 0)
			(layers "B.Cu" "B.Mask" "B.Paste")
			(net "SMB_PEHPCPU1_LVC3_SDA")
		)
	)
)
